(kicad_pcb
	(version 20260206)
	(generator "pcbnew")
	(generator_version "10.0")
	(general
		(thickness 1.6)
		(legacy_teardrops no)
	)
	(paper "A4")
	(title_block
		(title "12092022_DA0F0TFB6D0_F0T_FAN_BOARD_MP5048_D_brd_v02_OCP.brd")
		(comment 1 "Grand Teton / footprints 421-426 of 924")
	)
	(layers
		(0 "F.Cu" signal "TOP")
		(4 "In1.Cu" signal "GND")
		(6 "In2.Cu" signal "IN1")
		(8 "In3.Cu" signal "IN2")
		(10 "In4.Cu" signal "GND1")
		(2 "B.Cu" signal "BOTTOM")
		(9 "F.Adhes" user "F.Adhesive")
		(11 "B.Adhes" user "B.Adhesive")
		(13 "F.Paste" user "Package Geometry/Pastemask Top")
		(15 "B.Paste" user "Package Geometry/Pastemask Bottom")
		(5 "F.SilkS" user "Ref Des/Silkscreen Top")
		(7 "B.SilkS" user "Ref Des/Silkscreen Bottom")
		(1 "F.Mask" user "Board Geometry/Soldermask Top")
		(3 "B.Mask" user "Board Geometry/Soldermask Bottom")
		(17 "Dwgs.User" user "User.Drawings")
		(19 "Cmts.User" user "User.Comments")
		(21 "Eco1.User" user "User.Eco1")
		(23 "Eco2.User" user "User.Eco2")
		(25 "Edge.Cuts" user "Board Geometry/Outline")
		(27 "Margin" user)
		(31 "F.CrtYd" user "Package Geometry/Place Bound Top")
		(29 "B.CrtYd" user "Package Geometry/Place Bound Bottom")
		(35 "F.Fab" user "Ref Des/Assembly Top")
		(33 "B.Fab" user "Ref Des/Assembly Bottom")
	)
	(footprint ""
		(layer "F.Cu")
		(at 30.226 -121.92 90)
		(property "Reference" "R4936"
			(at 0 0 90)
			(layer "F.SilkS")
			(hide yes)
			(effects
				(font
					(size 1.27 1.27)
				)
			)
		)
		(property "Value" ""
			(at 0 0 90)
			(layer "F.Fab")
			(effects
				(font
					(size 1.27 1.27)
				)
			)
		)
		(duplicate_pad_numbers_are_jumpers no)
		(fp_line
			(start 0.7874 -0.4064)
			(end 0.7874 0.4064)
			(stroke
				(width 0.1524)
				(type default)
			)
			(layer "F.SilkS")
		)
		(fp_line
			(start -0.7874 -0.4064)
			(end 0.7874 -0.4064)
			(stroke
				(width 0.1524)
				(type default)
			)
			(layer "F.SilkS")
		)
		(fp_line
			(start 0.7874 0.4064)
			(end -0.7874 0.4064)
			(stroke
				(width 0.1524)
				(type default)
			)
			(layer "F.SilkS")
		)
		(fp_line
			(start -0.7874 0.4064)
			(end -0.7874 -0.4064)
			(stroke
				(width 0.1524)
				(type default)
			)
			(layer "F.SilkS")
		)
		(fp_line
			(start -0.12065 -0.305054)
			(end -0.12065 -0.2794)
			(stroke
				(width 0.1)
				(type default)
			)
			(layer "F.Fab")
		)
		(fp_line
			(start -0.67945 -0.305054)
			(end -0.12065 -0.305054)
			(stroke
				(width 0.1)
				(type default)
			)
			(layer "F.Fab")
		)
		(fp_line
			(start 0.67945 -0.3048)
			(end 0.67945 0.3048)
			(stroke
				(width 0.1)
				(type default)
			)
			(layer "F.Fab")
		)
		(fp_line
			(start 0.12065 -0.3048)
			(end 0.67945 -0.3048)
			(stroke
				(width 0.1)
				(type default)
			)
			(layer "F.Fab")
		)
		(fp_line
			(start 0.12065 -0.2794)
			(end 0.12065 -0.3048)
			(stroke
				(width 0.1)
				(type default)
			)
			(layer "F.Fab")
		)
		(fp_line
			(start -0.12065 -0.2794)
			(end 0.12065 -0.2794)
			(stroke
				(width 0.1)
				(type default)
			)
			(layer "F.Fab")
		)
		(fp_line
			(start 0.120396 0.2794)
			(end -0.12065 0.2794)
			(stroke
				(width 0.1)
				(type default)
			)
			(layer "F.Fab")
		)
		(fp_line
			(start -0.12065 0.2794)
			(end -0.12065 0.3048)
			(stroke
				(width 0.1)
				(type default)
			)
			(layer "F.Fab")
		)
		(fp_line
			(start 0.67945 0.3048)
			(end 0.120396 0.3048)
			(stroke
				(width 0.1)
				(type default)
			)
			(layer "F.Fab")
		)
		(fp_line
			(start 0.120396 0.3048)
			(end 0.120396 0.2794)
			(stroke
				(width 0.1)
				(type default)
			)
			(layer "F.Fab")
		)
		(fp_line
			(start -0.12065 0.3048)
			(end -0.67945 0.3048)
			(stroke
				(width 0.1)
				(type default)
			)
			(layer "F.Fab")
		)
		(fp_line
			(start -0.67945 0.3048)
			(end -0.67945 -0.305054)
			(stroke
				(width 0.1)
				(type default)
			)
			(layer "F.Fab")
		)
		(pad "1" smd circle
			(at -0.40005 0 90)
			(size 0 0)
			(layers "F.Cu" "F.Mask" "F.Paste")
			(net "GND")
		)
		(pad "2" smd circle
			(at 0.40005 0 90)
			(size 0 0)
			(layers "F.Cu" "F.Mask" "F.Paste")
			(net "MAX31790_U317_SPIN_START")
		)
	)
	(footprint ""
		(layer "F.Cu")
		(at 42.291 -260.477 180)
		(property "Reference" "PR7"
			(at 0 0 180)
			(layer "F.SilkS")
			(hide yes)
			(effects
				(font
					(size 1.27 1.27)
				)
			)
		)
		(property "Value" ""
			(at 0 0 180)
			(layer "F.Fab")
			(effects
				(font
					(size 1.27 1.27)
				)
			)
		)
		(duplicate_pad_numbers_are_jumpers no)
		(fp_line
			(start 0.7874 0.4064)
			(end -0.7874 0.4064)
			(stroke
				(width 0.1524)
				(type default)
			)
			(layer "F.SilkS")
		)
		(fp_line
			(start 0.7874 -0.4064)
			(end 0.7874 0.4064)
			(stroke
				(width 0.1524)
				(type default)
			)
			(layer "F.SilkS")
		)
		(fp_line
			(start -0.7874 0.4064)
			(end -0.7874 -0.4064)
			(stroke
				(width 0.1524)
				(type default)
			)
			(layer "F.SilkS")
		)
		(fp_line
			(start -0.7874 -0.4064)
			(end 0.7874 -0.4064)
			(stroke
				(width 0.1524)
				(type default)
			)
			(layer "F.SilkS")
		)
		(fp_line
			(start 0.67945 0.3048)
			(end 0.120396 0.3048)
			(stroke
				(width 0.1)
				(type default)
			)
			(layer "F.Fab")
		)
		(fp_line
			(start 0.67945 -0.3048)
			(end 0.67945 0.3048)
			(stroke
				(width 0.1)
				(type default)
			)
			(layer "F.Fab")
		)
		(fp_line
			(start 0.12065 -0.2794)
			(end 0.12065 -0.3048)
			(stroke
				(width 0.1)
				(type default)
			)
			(layer "F.Fab")
		)
		(fp_line
			(start 0.12065 -0.3048)
			(end 0.67945 -0.3048)
			(stroke
				(width 0.1)
				(type default)
			)
			(layer "F.Fab")
		)
		(fp_line
			(start 0.120396 0.3048)
			(end 0.120396 0.2794)
			(stroke
				(width 0.1)
				(type default)
			)
			(layer "F.Fab")
		)
		(fp_line
			(start 0.120396 0.2794)
			(end -0.12065 0.2794)
			(stroke
				(width 0.1)
				(type default)
			)
			(layer "F.Fab")
		)
		(fp_line
			(start -0.12065 0.3048)
			(end -0.67945 0.3048)
			(stroke
				(width 0.1)
				(type default)
			)
			(layer "F.Fab")
		)
		(fp_line
			(start -0.12065 0.2794)
			(end -0.12065 0.3048)
			(stroke
				(width 0.1)
				(type default)
			)
			(layer "F.Fab")
		)
		(fp_line
			(start -0.12065 -0.2794)
			(end 0.12065 -0.2794)
			(stroke
				(width 0.1)
				(type default)
			)
			(layer "F.Fab")
		)
		(fp_line
			(start -0.12065 -0.305054)
			(end -0.12065 -0.2794)
			(stroke
				(width 0.1)
				(type default)
			)
			(layer "F.Fab")
		)
		(fp_line
			(start -0.67945 0.3048)
			(end -0.67945 -0.305054)
			(stroke
				(width 0.1)
				(type default)
			)
			(layer "F.Fab")
		)
		(fp_line
			(start -0.67945 -0.305054)
			(end -0.12065 -0.305054)
			(stroke
				(width 0.1)
				(type default)
			)
			(layer "F.Fab")
		)
		(pad "1" smd circle
			(at -0.40005 0 180)
			(size 0 0)
			(layers "F.Cu" "F.Mask" "F.Paste")
			(net "FAN_0_MODE")
		)
		(pad "2" smd circle
			(at 0.40005 0 180)
			(size 0 0)
			(layers "F.Cu" "F.Mask" "F.Paste")
			(net "GND")
		)
	)
	(footprint ""
		(layer "F.Cu")
		(at 14.859 -125.857)
		(property "Reference" "R5612"
			(at 0 0 0)
			(layer "F.SilkS")
			(hide yes)
			(effects
				(font
					(size 1.27 1.27)
				)
			)
		)
		(property "Value" ""
			(at 0 0 0)
			(layer "F.Fab")
			(effects
				(font
					(size 1.27 1.27)
				)
			)
		)
		(duplicate_pad_numbers_are_jumpers no)
		(fp_line
			(start -0.7874 -0.4064)
			(end 0.7874 -0.4064)
			(stroke
				(width 0.1524)
				(type default)
			)
			(layer "F.SilkS")
		)
		(fp_line
			(start -0.7874 0.4064)
			(end -0.7874 -0.4064)
			(stroke
				(width 0.1524)
				(type default)
			)
			(layer "F.SilkS")
		)
		(fp_line
			(start 0.7874 -0.4064)
			(end 0.7874 0.4064)
			(stroke
				(width 0.1524)
				(type default)
			)
			(layer "F.SilkS")
		)
		(fp_line
			(start 0.7874 0.4064)
			(end -0.7874 0.4064)
			(stroke
				(width 0.1524)
				(type default)
			)
			(layer "F.SilkS")
		)
		(fp_line
			(start -0.67945 -0.305054)
			(end -0.12065 -0.305054)
			(stroke
				(width 0.1)
				(type default)
			)
			(layer "F.Fab")
		)
		(fp_line
			(start -0.67945 0.3048)
			(end -0.67945 -0.305054)
			(stroke
				(width 0.1)
				(type default)
			)
			(layer "F.Fab")
		)
		(fp_line
			(start -0.12065 -0.305054)
			(end -0.12065 -0.2794)
			(stroke
				(width 0.1)
				(type default)
			)
			(layer "F.Fab")
		)
		(fp_line
			(start -0.12065 -0.2794)
			(end 0.12065 -0.2794)
			(stroke
				(width 0.1)
				(type default)
			)
			(layer "F.Fab")
		)
		(fp_line
			(start -0.12065 0.2794)
			(end -0.12065 0.3048)
			(stroke
				(width 0.1)
				(type default)
			)
			(layer "F.Fab")
		)
		(fp_line
			(start -0.12065 0.3048)
			(end -0.67945 0.3048)
			(stroke
				(width 0.1)
				(type default)
			)
			(layer "F.Fab")
		)
		(fp_line
			(start 0.120396 0.2794)
			(end -0.12065 0.2794)
			(stroke
				(width 0.1)
				(type default)
			)
			(layer "F.Fab")
		)
		(fp_line
			(start 0.120396 0.3048)
			(end 0.120396 0.2794)
			(stroke
				(width 0.1)
				(type default)
			)
			(layer "F.Fab")
		)
		(fp_line
			(start 0.12065 -0.3048)
			(end 0.67945 -0.3048)
			(stroke
				(width 0.1)
				(type default)
			)
			(layer "F.Fab")
		)
		(fp_line
			(start 0.12065 -0.2794)
			(end 0.12065 -0.3048)
			(stroke
				(width 0.1)
				(type default)
			)
			(layer "F.Fab")
		)
		(fp_line
			(start 0.67945 -0.3048)
			(end 0.67945 0.3048)
			(stroke
				(width 0.1)
				(type default)
			)
			(layer "F.Fab")
		)
		(fp_line
			(start 0.67945 0.3048)
			(end 0.120396 0.3048)
			(stroke
				(width 0.1)
				(type default)
			)
			(layer "F.Fab")
		)
		(pad "1" smd rect
			(at -0.40005 0 180)
			(size 0.4572 0.508)
			(layers "F.Cu" "F.Mask" "F.Paste")
			(net "FAN_4_TACH_OL")
		)
		(pad "2" smd rect
			(at 0.40005 0 180)
			(size 0.4572 0.508)
			(layers "F.Cu" "F.Mask" "F.Paste")
			(net "FAN_4_TACH_OL_R1")
		)
	)
	(footprint ""
		(layer "F.Cu")
		(at 6.096 -63.881 180)
		(property "Reference" "PR51"
			(at 0 0 180)
			(layer "F.SilkS")
			(hide yes)
			(effects
				(font
					(size 1.27 1.27)
				)
			)
		)
		(property "Value" ""
			(at 0 0 180)
			(layer "F.Fab")
			(effects
				(font
					(size 1.27 1.27)
				)
			)
		)
		(duplicate_pad_numbers_are_jumpers no)
		(fp_line
			(start 0.7874 0.4064)
			(end -0.7874 0.4064)
			(stroke
				(width 0.1524)
				(type default)
			)
			(layer "F.SilkS")
		)
		(fp_line
			(start 0.7874 -0.4064)
			(end 0.7874 0.4064)
			(stroke
				(width 0.1524)
				(type default)
			)
			(layer "F.SilkS")
		)
		(fp_line
			(start -0.7874 0.4064)
			(end -0.7874 -0.4064)
			(stroke
				(width 0.1524)
				(type default)
			)
			(layer "F.SilkS")
		)
		(fp_line
			(start -0.7874 -0.4064)
			(end 0.7874 -0.4064)
			(stroke
				(width 0.1524)
				(type default)
			)
			(layer "F.SilkS")
		)
		(fp_line
			(start 0.67945 0.3048)
			(end 0.120396 0.3048)
			(stroke
				(width 0.1)
				(type default)
			)
			(layer "F.Fab")
		)
		(fp_line
			(start 0.67945 -0.3048)
			(end 0.67945 0.3048)
			(stroke
				(width 0.1)
				(type default)
			)
			(layer "F.Fab")
		)
		(fp_line
			(start 0.12065 -0.2794)
			(end 0.12065 -0.3048)
			(stroke
				(width 0.1)
				(type default)
			)
			(layer "F.Fab")
		)
		(fp_line
			(start 0.12065 -0.3048)
			(end 0.67945 -0.3048)
			(stroke
				(width 0.1)
				(type default)
			)
			(layer "F.Fab")
		)
		(fp_line
			(start 0.120396 0.3048)
			(end 0.120396 0.2794)
			(stroke
				(width 0.1)
				(type default)
			)
			(layer "F.Fab")
		)
		(fp_line
			(start 0.120396 0.2794)
			(end -0.12065 0.2794)
			(stroke
				(width 0.1)
				(type default)
			)
			(layer "F.Fab")
		)
		(fp_line
			(start -0.12065 0.3048)
			(end -0.67945 0.3048)
			(stroke
				(width 0.1)
				(type default)
			)
			(layer "F.Fab")
		)
		(fp_line
			(start -0.12065 0.2794)
			(end -0.12065 0.3048)
			(stroke
				(width 0.1)
				(type default)
			)
			(layer "F.Fab")
		)
		(fp_line
			(start -0.12065 -0.2794)
			(end 0.12065 -0.2794)
			(stroke
				(width 0.1)
				(type default)
			)
			(layer "F.Fab")
		)
		(fp_line
			(start -0.12065 -0.305054)
			(end -0.12065 -0.2794)
			(stroke
				(width 0.1)
				(type default)
			)
			(layer "F.Fab")
		)
		(fp_line
			(start -0.67945 0.3048)
			(end -0.67945 -0.305054)
			(stroke
				(width 0.1)
				(type default)
			)
			(layer "F.Fab")
		)
		(fp_line
			(start -0.67945 -0.305054)
			(end -0.12065 -0.305054)
			(stroke
				(width 0.1)
				(type default)
			)
			(layer "F.Fab")
		)
		(pad "1" smd circle
			(at -0.40005 0 180)
			(size 0 0)
			(layers "F.Cu" "F.Mask" "F.Paste")
			(net "FAN_4_MODE")
		)
		(pad "2" smd circle
			(at 0.40005 0 180)
			(size 0 0)
			(layers "F.Cu" "F.Mask" "F.Paste")
			(net "GND")
		)
	)
	(footprint ""
		(layer "F.Cu")
		(at 14.605 -203.073 90)
		(property "Reference" "R5699"
			(at 0 0 90)
			(layer "F.SilkS")
			(hide yes)
			(effects
				(font
					(size 1.27 1.27)
				)
			)
		)
		(property "Value" ""
			(at 0 0 90)
			(layer "F.Fab")
			(effects
				(font
					(size 1.27 1.27)
				)
			)
		)
		(duplicate_pad_numbers_are_jumpers no)
		(fp_line
			(start 0.7874 -0.4064)
			(end 0.7874 0.4064)
			(stroke
				(width 0.1524)
				(type default)
			)
			(layer "F.SilkS")
		)
		(fp_line
			(start -0.7874 -0.4064)
			(end 0.7874 -0.4064)
			(stroke
				(width 0.1524)
				(type default)
			)
			(layer "F.SilkS")
		)
		(fp_line
			(start 0.7874 0.4064)
			(end -0.7874 0.4064)
			(stroke
				(width 0.1524)
				(type default)
			)
			(layer "F.SilkS")
		)
		(fp_line
			(start -0.7874 0.4064)
			(end -0.7874 -0.4064)
			(stroke
				(width 0.1524)
				(type default)
			)
			(layer "F.SilkS")
		)
		(fp_line
			(start -0.12065 -0.305054)
			(end -0.12065 -0.2794)
			(stroke
				(width 0.1)
				(type default)
			)
			(layer "F.Fab")
		)
		(fp_line
			(start -0.67945 -0.305054)
			(end -0.12065 -0.305054)
			(stroke
				(width 0.1)
				(type default)
			)
			(layer "F.Fab")
		)
		(fp_line
			(start 0.67945 -0.3048)
			(end 0.67945 0.3048)
			(stroke
				(width 0.1)
				(type default)
			)
			(layer "F.Fab")
		)
		(fp_line
			(start 0.12065 -0.3048)
			(end 0.67945 -0.3048)
			(stroke
				(width 0.1)
				(type default)
			)
			(layer "F.Fab")
		)
		(fp_line
			(start 0.12065 -0.2794)
			(end 0.12065 -0.3048)
			(stroke
				(width 0.1)
				(type default)
			)
			(layer "F.Fab")
		)
		(fp_line
			(start -0.12065 -0.2794)
			(end 0.12065 -0.2794)
			(stroke
				(width 0.1)
				(type default)
			)
			(layer "F.Fab")
		)
		(fp_line
			(start 0.120396 0.2794)
			(end -0.12065 0.2794)
			(stroke
				(width 0.1)
				(type default)
			)
			(layer "F.Fab")
		)
		(fp_line
			(start -0.12065 0.2794)
			(end -0.12065 0.3048)
			(stroke
				(width 0.1)
				(type default)
			)
			(layer "F.Fab")
		)
		(fp_line
			(start 0.67945 0.3048)
			(end 0.120396 0.3048)
			(stroke
				(width 0.1)
				(type default)
			)
			(layer "F.Fab")
		)
		(fp_line
			(start 0.120396 0.3048)
			(end 0.120396 0.2794)
			(stroke
				(width 0.1)
				(type default)
			)
			(layer "F.Fab")
		)
		(fp_line
			(start -0.12065 0.3048)
			(end -0.67945 0.3048)
			(stroke
				(width 0.1)
				(type default)
			)
			(layer "F.Fab")
		)
		(fp_line
			(start -0.67945 0.3048)
			(end -0.67945 -0.305054)
			(stroke
				(width 0.1)
				(type default)
			)
			(layer "F.Fab")
		)
		(pad "1" smd rect
			(at -0.40005 0 270)
			(size 0.4572 0.508)
			(layers "F.Cu" "F.Mask" "F.Paste")
			(net "P12V_LED_FAN6")
		)
		(pad "2" smd rect
			(at 0.40005 0 270)
			(size 0.4572 0.508)
			(layers "F.Cu" "F.Mask" "F.Paste")
			(net "P12V_LED_R_FAN6")
		)
	)
	(footprint ""
		(layer "F.Cu")
		(at 11.938 -98.552 180)
		(property "Reference" "U410"
			(at 1.17602 1.82499 0)
			(unlocked yes)
			(layer "F.SilkS")
			(effects
				(font
					(size 0.7874 0.5842)
					(thickness 0.1524)
				)
				(justify left)
			)
		)
		(property "Value" ""
			(at 0 0 180)
			(layer "F.Fab")
			(effects
				(font
					(size 1.27 1.27)
				)
			)
		)
		(duplicate_pad_numbers_are_jumpers no)
		(fp_line
			(start 1.335278 1.100074)
			(end 1.335278 -1.100074)
			(stroke
				(width 0.1524)
				(type default)
			)
			(layer "F.SilkS")
		)
		(fp_line
			(start 1.335278 -1.100074)
			(end -1.335278 -1.100074)
			(stroke
				(width 0.1524)
				(type default)
			)
			(layer "F.SilkS")
		)
		(fp_line
			(start -1.335278 1.100074)
			(end 1.335278 1.100074)
			(stroke
				(width 0.1524)
				(type default)
			)
			(layer "F.SilkS")
		)
		(fp_line
			(start -1.335278 -1.100074)
			(end -1.335278 1.100074)
			(stroke
				(width 0.1524)
				(type default)
			)
			(layer "F.SilkS")
		)
		(fp_line
			(start 0.674878 1.100074)
			(end 0.674878 -1.100074)
			(stroke
				(width 0.1)
				(type default)
			)
			(layer "F.Fab")
		)
		(fp_line
			(start 0.674878 -1.100074)
			(end -0.674878 -1.100074)
			(stroke
				(width 0.1)
				(type default)
			)
			(layer "F.Fab")
		)
		(fp_line
			(start -0.674878 1.100074)
			(end 0.674878 1.100074)
			(stroke
				(width 0.1)
				(type default)
			)
			(layer "F.Fab")
		)
		(fp_line
			(start -0.674878 -1.100074)
			(end -0.674878 1.100074)
			(stroke
				(width 0.1)
				(type default)
			)
			(layer "F.Fab")
		)
		(pad "D" smd rect
			(at 0.8001 0 90)
			(size 0.6096 0.8128)
			(layers "F.Cu" "F.Mask" "F.Paste")
			(net "U410_D1")
		)
		(pad "G" smd rect
			(at -0.8001 -0.649986 90)
			(size 0.6096 0.8128)
			(layers "F.Cu" "F.Mask" "F.Paste")
			(net "FAN_5_PRESENT")
		)
		(pad "S" smd rect
			(at -0.8001 0.649986 90)
			(size 0.6096 0.8128)
			(layers "F.Cu" "F.Mask" "F.Paste")
			(net "GND")
		)
	)
)
